# BASEBOARD_FAB2 (Tioga Pass) — schematic netlist excerpt (pin names and nets, part order shuffled) for the footprints in the layout excerpt that follows; sources: Cadence DE-HDL packaged netlist, KiCad conversion of Wiwynn_Tioga_Pass_MB.brd

C25W62  CAP  4.7UF 6.3V 10% X6S  pkg 0603  page 149 : A = P3V3_STBY ; B = GND
R3U9  RES  0.0 5% CHIP  pkg 0402  page 216 : A = VR_PVDDQ_ABC_PH2_VCIN ; B = P5V_STBY
R25W138  RES  33.2 1% CHIP  pkg 0402  page 252 : A = VGA_REAR_HSYNC_S ; B = V_IO_HSYNC_J

(kicad_pcb
	(version 20260206)
	(generator "pcbnew")
	(generator_version "10.0")
	(general
		(thickness 1.6)
		(legacy_teardrops no)
	)
	(paper "A4")
	(title_block
		(title "Wiwynn_Tioga_Pass_MB.brd")
		(comment 1 "Tioga Pass / footprints 3818-3820 of 4770")
	)
	(layers
		(0 "F.Cu" signal "TOP")
		(4 "In1.Cu" signal "L2GND")
		(6 "In2.Cu" signal "L3")
		(8 "In3.Cu" signal "L4GND")
		(10 "In4.Cu" signal "L5")
		(12 "In5.Cu" signal "L6GND")
		(14 "In6.Cu" signal "L7VCC")
		(16 "In7.Cu" signal "L8VCC")
		(18 "In8.Cu" signal "L9GND")
		(20 "In9.Cu" signal "L10")
		(22 "In10.Cu" signal "L11GND")
		(24 "In11.Cu" signal "L12")
		(26 "In12.Cu" signal "L13GND")
		(2 "B.Cu" signal "BOTTOM")
		(9 "F.Adhes" user "F.Adhesive")
		(11 "B.Adhes" user "B.Adhesive")
		(13 "F.Paste" user "Package Geometry/Pastemask Top")
		(15 "B.Paste" user "Package Geometry/Pastemask Bottom")
		(5 "F.SilkS" user "Ref Des/Silkscreen Top")
		(7 "B.SilkS" user "Ref Des/Silkscreen Bottom")
		(1 "F.Mask" user "Board Geometry/Soldermask Top")
		(3 "B.Mask" user "Board Geometry/Soldermask Bottom")
		(17 "Dwgs.User" user "User.Drawings")
		(19 "Cmts.User" user "User.Comments")
		(21 "Eco1.User" user "User.Eco1")
		(23 "Eco2.User" user "User.Eco2")
		(25 "Edge.Cuts" user "Board Geometry/Outline")
		(27 "Margin" user)
		(31 "F.CrtYd" user "Package Geometry/Place Bound Top")
		(29 "B.CrtYd" user "Package Geometry/Place Bound Bottom")
		(35 "F.Fab" user "Ref Des/Assembly Top")
		(33 "B.Fab" user "Ref Des/Assembly Bottom")
	)
	(footprint ""
		(layer "B.Cu")
		(at 493.644428 -41.405048 180)
		(property "Reference" "R25W138"
			(at 0.8382 -0.67818 180)
			(unlocked yes)
			(layer "B.SilkS")
			(effects
				(font
					(size 0.4064 0.254)
					(thickness 0.1524)
				)
				(justify left mirror)
			)
		)
		(property "Value" ""
			(at 0 0 0)
			(layer "B.Fab")
			(effects
				(font
					(size 1.27 1.27)
				)
				(justify mirror)
			)
		)
		(duplicate_pad_numbers_are_jumpers no)
		(fp_poly
			(pts
				(xy 0.2794 -0.1016) (xy -0.2794 -0.1016) (xy -0.2794 0.9906) (xy 0.2794 0.9906)
			)
			(stroke
				(width 0)
				(type default)
			)
			(fill no)
			(layer "B.CrtYd")
		)
		(fp_line
			(start 0.2794 0.9906)
			(end -0.2794 0.9906)
			(stroke
				(width 0.1)
				(type default)
			)
			(layer "B.Fab")
		)
		(fp_line
			(start 0.2794 -0.1016)
			(end 0.2794 0.9906)
			(stroke
				(width 0.1)
				(type default)
			)
			(layer "B.Fab")
		)
		(fp_line
			(start -0.2794 0.9906)
			(end -0.2794 -0.1016)
			(stroke
				(width 0.1)
				(type default)
			)
			(layer "B.Fab")
		)
		(fp_line
			(start -0.2794 -0.1016)
			(end 0.2794 -0.1016)
			(stroke
				(width 0.1)
				(type default)
			)
			(layer "B.Fab")
		)
		(pad "1" smd rect
			(at 0 0)
			(size 0.508 0.508)
			(layers "B.Cu" "B.Mask" "B.Paste")
			(net "VGA_REAR_HSYNC_S")
		)
		(pad "2" smd rect
			(at 0 0.889)
			(size 0.508 0.508)
			(layers "B.Cu" "B.Mask" "B.Paste")
			(net "V_IO_HSYNC_J")
		)
		(zone
			(layer "B.Cu")
			(hatch none 0.5)
			(connect_pads
				(clearance 0)
			)
			(min_thickness 0.25)
			(keepout
				(tracks not_allowed)
				(vias allowed)
				(pads allowed)
				(copperpour not_allowed)
				(footprints allowed)
			)
			(placement
				(enabled no)
				(sheetname "")
			)
			(fill
				(thermal_gap 0.5)
				(thermal_bridge_width 0.5)
				(island_removal_mode 0)
			)
			(polygon
				(pts
					(xy 493.390428 -42.040048) (xy 493.898428 -42.040048) (xy 493.898428 -41.659048) (xy 493.390428 -41.659048)
				)
			)
		)
		(zone
			(layer "B.Cu")
			(hatch none 0.5)
			(connect_pads
				(clearance 0)
			)
			(min_thickness 0.25)
			(keepout
				(tracks allowed)
				(vias not_allowed)
				(pads allowed)
				(copperpour not_allowed)
				(footprints allowed)
			)
			(placement
				(enabled no)
				(sheetname "")
			)
			(fill
				(thermal_gap 0.5)
				(thermal_bridge_width 0.5)
				(island_removal_mode 0)
			)
			(polygon
				(pts
					(xy 493.390428 -41.659048) (xy 493.898428 -41.659048) (xy 493.898428 -42.040048) (xy 493.390428 -42.040048)
				)
			)
		)
	)
	(footprint ""
		(layer "B.Cu")
		(at 348.129606 -0.679704 -90)
		(property "Reference" "R3U9"
			(at 0 0 90)
			(layer "B.SilkS")
			(hide yes)
			(effects
				(font
					(size 1.27 1.27)
				)
				(justify mirror)
			)
		)
		(property "Value" ""
			(at 0 0 90)
			(layer "B.Fab")
			(effects
				(font
					(size 1.27 1.27)
				)
				(justify mirror)
			)
		)
		(duplicate_pad_numbers_are_jumpers no)
		(fp_rect
			(start -0.2794 0.9906)
			(end 0.2794 -0.1016)
			(stroke
				(width 0)
				(type default)
			)
			(fill no)
			(layer "B.CrtYd")
		)
		(fp_line
			(start -0.2794 0.9906)
			(end -0.2794 -0.1016)
			(stroke
				(width 0.1)
				(type default)
			)
			(layer "B.Fab")
		)
		(fp_line
			(start 0.2794 0.9906)
			(end -0.2794 0.9906)
			(stroke
				(width 0.1)
				(type default)
			)
			(layer "B.Fab")
		)
		(fp_line
			(start -0.2794 -0.1016)
			(end 0.2794 -0.1016)
			(stroke
				(width 0.1)
				(type default)
			)
			(layer "B.Fab")
		)
		(fp_line
			(start 0.2794 -0.1016)
			(end 0.2794 0.9906)
			(stroke
				(width 0.1)
				(type default)
			)
			(layer "B.Fab")
		)
		(pad "1" smd rect
			(at 0 0 90)
			(size 0.508 0.508)
			(layers "B.Cu" "B.Mask" "B.Paste")
			(net "VR_PVDDQ_ABC_PH2_VCIN")
		)
		(pad "2" smd rect
			(at 0 0.889 90)
			(size 0.508 0.508)
			(layers "B.Cu" "B.Mask" "B.Paste")
			(net "P5V_STBY")
		)
		(zone
			(layer "B.Cu")
			(hatch none 0.5)
			(connect_pads
				(clearance 0)
			)
			(min_thickness 0.25)
			(keepout
				(tracks not_allowed)
				(vias allowed)
				(pads allowed)
				(copperpour not_allowed)
				(footprints allowed)
			)
			(placement
				(enabled no)
				(sheetname "")
			)
			(fill
				(thermal_gap 0.5)
				(thermal_bridge_width 0.5)
				(island_removal_mode 0)
			)
			(polygon
				(pts
					(xy 347.494606 -0.933704) (xy 347.494606 -0.425704) (xy 347.875606 -0.425704) (xy 347.875606 -0.933704)
				)
			)
		)
		(zone
			(layer "B.Cu")
			(hatch none 0.5)
			(connect_pads
				(clearance 0)
			)
			(min_thickness 0.25)
			(keepout
				(tracks allowed)
				(vias not_allowed)
				(pads allowed)
				(copperpour not_allowed)
				(footprints allowed)
			)
			(placement
				(enabled no)
				(sheetname "")
			)
			(fill
				(thermal_gap 0.5)
				(thermal_bridge_width 0.5)
				(island_removal_mode 0)
			)
			(polygon
				(pts
					(xy 347.494606 -0.933704) (xy 347.494606 -0.425704) (xy 347.875606 -0.425704) (xy 347.875606 -0.933704)
				)
			)
		)
	)
	(footprint ""
		(layer "B.Cu")
		(at 405.8285 -22.987 -90)
		(property "Reference" "C25W62"
			(at -0.97536 0.76708 0)
			(unlocked yes)
			(layer "B.SilkS")
			(effects
				(font
					(size 0.4064 0.254)
					(thickness 0.1524)
				)
				(justify mirror)
			)
		)
		(property "Value" ""
			(at 0 0 90)
			(layer "B.Fab")
			(effects
				(font
					(size 1.27 1.27)
				)
				(justify mirror)
			)
		)
		(duplicate_pad_numbers_are_jumpers no)
		(fp_poly
			(pts
				(xy 0.4953 -0.2032) (xy -0.4953 -0.2032) (xy -0.4953 1.6002) (xy 0.4953 1.6002)
			)
			(stroke
				(width 0)
				(type default)
			)
			(fill no)
			(layer "B.CrtYd")
		)
		(fp_line
			(start -0.4953 1.6002)
			(end 0.4953 1.6002)
			(stroke
				(width 0.1)
				(type default)
			)
			(layer "B.Fab")
		)
		(fp_line
			(start 0.4953 1.6002)
			(end 0.4953 -0.2032)
			(stroke
				(width 0.1)
				(type default)
			)
			(layer "B.Fab")
		)
		(fp_line
			(start -0.4953 -0.2032)
			(end -0.4953 1.6002)
			(stroke
				(width 0.1)
				(type default)
			)
			(layer "B.Fab")
		)
		(fp_line
			(start 0.4953 -0.2032)
			(end -0.4953 -0.2032)
			(stroke
				(width 0.1)
				(type default)
			)
			(layer "B.Fab")
		)
		(pad "1" smd rect
			(at 0 0 90)
			(size 0.762 0.889)
			(layers "B.Cu" "B.Mask" "B.Paste")
			(net "P3V3_STBY")
		)
		(pad "2" smd rect
			(at 0 1.397 90)
			(size 0.762 0.889)
			(layers "B.Cu" "B.Mask" "B.Paste")
			(net "GND")
		)
		(zone
			(layer "B.Cu")
			(hatch none 0.5)
			(connect_pads
				(clearance 0)
			)
			(min_thickness 0.25)
			(keepout
				(tracks not_allowed)
				(vias allowed)
				(pads allowed)
				(copperpour not_allowed)
				(footprints allowed)
			)
			(placement
				(enabled no)
				(sheetname "")
			)
			(fill
				(thermal_gap 0.5)
				(thermal_bridge_width 0.5)
				(island_removal_mode 0)
			)
			(polygon
				(pts
					(xy 405.384 -22.606) (xy 405.384 -23.368) (xy 404.876 -23.368) (xy 404.876 -22.606)
				)
			)
		)
	)
)
